(kicad_pcb
	(version 20260206)
	(generator "pcbnew")
	(generator_version "10.0")
	(general
		(thickness 1.6)
		(legacy_teardrops no)
	)
	(paper "A4")
	(title_block
		(title "01162023_DA0F0TEBIF0_F0T_Expander_BD_F_brd_V02_OCP.brd")
		(comment 1 "Grand Teton / footprints 2370-2375 of 9728")
	)
	(layers
		(0 "F.Cu" signal "TOP")
		(4 "In1.Cu" signal "GND")
		(6 "In2.Cu" signal "VCC")
		(8 "In3.Cu" signal "VCC1")
		(10 "In4.Cu" signal "GND1")
		(12 "In5.Cu" signal "IN1")
		(14 "In6.Cu" signal "GND2")
		(16 "In7.Cu" signal "IN2")
		(18 "In8.Cu" signal "GND3")
		(20 "In9.Cu" signal "IN3")
		(22 "In10.Cu" signal "GND4")
		(24 "In11.Cu" signal "IN4")
		(26 "In12.Cu" signal "GND5")
		(28 "In13.Cu" signal "IN5")
		(30 "In14.Cu" signal "GND6")
		(32 "In15.Cu" signal "IN6")
		(34 "In16.Cu" signal "GND7")
		(2 "B.Cu" signal "BOTTOM")
		(9 "F.Adhes" user "F.Adhesive")
		(11 "B.Adhes" user "B.Adhesive")
		(13 "F.Paste" user "Package Geometry/Pastemask Top")
		(15 "B.Paste" user "Package Geometry/Pastemask Bottom")
		(5 "F.SilkS" user "Ref Des/Silkscreen Top")
		(7 "B.SilkS" user "Ref Des/Silkscreen Bottom")
		(1 "F.Mask" user "Board Geometry/Soldermask Top")
		(3 "B.Mask" user "Board Geometry/Soldermask Bottom")
		(17 "Dwgs.User" user "User.Drawings")
		(19 "Cmts.User" user "User.Comments")
		(21 "Eco1.User" user "User.Eco1")
		(23 "Eco2.User" user "User.Eco2")
		(25 "Edge.Cuts" user "Board Geometry/Outline")
		(27 "Margin" user)
		(31 "F.CrtYd" user "Package Geometry/Place Bound Top")
		(29 "B.CrtYd" user "Package Geometry/Place Bound Bottom")
		(35 "F.Fab" user "Ref Des/Assembly Top")
		(33 "B.Fab" user "Ref Des/Assembly Bottom")
	)
	(footprint ""
		(layer "F.Cu")
		(at 19.526758 -55.418228 90)
		(property "Reference" "PC356"
			(at 0 0 90)
			(layer "F.SilkS")
			(hide yes)
			(effects
				(font
					(size 1.27 1.27)
				)
			)
		)
		(property "Value" ""
			(at 0 0 90)
			(layer "F.Fab")
			(effects
				(font
					(size 1.27 1.27)
				)
			)
		)
		(duplicate_pad_numbers_are_jumpers no)
		(fp_line
			(start 0.7874 -0.4064)
			(end 0.7874 0.4064)
			(stroke
				(width 0.1524)
				(type default)
			)
			(layer "F.SilkS")
		)
		(fp_line
			(start -0.7874 -0.4064)
			(end 0.7874 -0.4064)
			(stroke
				(width 0.1524)
				(type default)
			)
			(layer "F.SilkS")
		)
		(fp_line
			(start 0.7874 0.4064)
			(end -0.7874 0.4064)
			(stroke
				(width 0.1524)
				(type default)
			)
			(layer "F.SilkS")
		)
		(fp_line
			(start -0.7874 0.4064)
			(end -0.7874 -0.4064)
			(stroke
				(width 0.1524)
				(type default)
			)
			(layer "F.SilkS")
		)
		(fp_line
			(start -0.12065 -0.305054)
			(end -0.12065 -0.2794)
			(stroke
				(width 0.1)
				(type default)
			)
			(layer "F.Fab")
		)
		(fp_line
			(start -0.67945 -0.305054)
			(end -0.12065 -0.305054)
			(stroke
				(width 0.1)
				(type default)
			)
			(layer "F.Fab")
		)
		(fp_line
			(start 0.67945 -0.3048)
			(end 0.67945 0.3048)
			(stroke
				(width 0.1)
				(type default)
			)
			(layer "F.Fab")
		)
		(fp_line
			(start 0.12065 -0.3048)
			(end 0.67945 -0.3048)
			(stroke
				(width 0.1)
				(type default)
			)
			(layer "F.Fab")
		)
		(fp_line
			(start 0.12065 -0.2794)
			(end 0.12065 -0.3048)
			(stroke
				(width 0.1)
				(type default)
			)
			(layer "F.Fab")
		)
		(fp_line
			(start -0.12065 -0.2794)
			(end 0.12065 -0.2794)
			(stroke
				(width 0.1)
				(type default)
			)
			(layer "F.Fab")
		)
		(fp_line
			(start 0.120396 0.2794)
			(end -0.12065 0.2794)
			(stroke
				(width 0.1)
				(type default)
			)
			(layer "F.Fab")
		)
		(fp_line
			(start -0.12065 0.2794)
			(end -0.12065 0.3048)
			(stroke
				(width 0.1)
				(type default)
			)
			(layer "F.Fab")
		)
		(fp_line
			(start 0.67945 0.3048)
			(end 0.120396 0.3048)
			(stroke
				(width 0.1)
				(type default)
			)
			(layer "F.Fab")
		)
		(fp_line
			(start 0.120396 0.3048)
			(end 0.120396 0.2794)
			(stroke
				(width 0.1)
				(type default)
			)
			(layer "F.Fab")
		)
		(fp_line
			(start -0.12065 0.3048)
			(end -0.67945 0.3048)
			(stroke
				(width 0.1)
				(type default)
			)
			(layer "F.Fab")
		)
		(fp_line
			(start -0.67945 0.3048)
			(end -0.67945 -0.305054)
			(stroke
				(width 0.1)
				(type default)
			)
			(layer "F.Fab")
		)
		(pad "1" smd circle
			(at -0.40005 0 90)
			(size 0 0)
			(layers "F.Cu" "F.Mask" "F.Paste")
			(net "P12V_SSD0_R")
		)
		(pad "2" smd circle
			(at 0.40005 0 90)
			(size 0 0)
			(layers "F.Cu" "F.Mask" "F.Paste")
			(net "GND")
		)
	)
	(footprint ""
		(layer "F.Cu")
		(at 430.961546 -120.476772 180)
		(property "Reference" "C663"
			(at 0 0 180)
			(layer "F.SilkS")
			(hide yes)
			(effects
				(font
					(size 1.27 1.27)
				)
			)
		)
		(property "Value" ""
			(at 0 0 180)
			(layer "F.Fab")
			(effects
				(font
					(size 1.27 1.27)
				)
			)
		)
		(duplicate_pad_numbers_are_jumpers no)
		(fp_line
			(start 0.299974 0.150114)
			(end -0.299974 0.150114)
			(stroke
				(width 0.1)
				(type default)
			)
			(layer "F.Fab")
		)
		(fp_line
			(start 0.299974 -0.150114)
			(end 0.299974 0.150114)
			(stroke
				(width 0.1)
				(type default)
			)
			(layer "F.Fab")
		)
		(fp_line
			(start -0.299974 0.150114)
			(end -0.299974 -0.150114)
			(stroke
				(width 0.1)
				(type default)
			)
			(layer "F.Fab")
		)
		(fp_line
			(start -0.299974 -0.150114)
			(end 0.299974 -0.150114)
			(stroke
				(width 0.1)
				(type default)
			)
			(layer "F.Fab")
		)
		(pad "1" smd rect
			(at -0.2667 0 180)
			(size 0.3048 0.381)
			(layers "F.Cu" "F.Mask" "F.Paste")
			(net "P5E_PEX3_STN0_TX_DN<1>")
		)
		(pad "2" smd rect
			(at 0.2667 0 180)
			(size 0.3048 0.381)
			(layers "F.Cu" "F.Mask" "F.Paste")
			(net "P5E_PEX3_STN0_TX_C_DN<1>")
		)
	)
	(footprint ""
		(layer "F.Cu")
		(at 263.335008 -369.930426 90)
		(property "Reference" "PQ6605"
			(at -8.22325 -1.874774 0)
			(unlocked yes)
			(layer "F.SilkS")
			(effects
				(font
					(size 0.7874 0.5842)
					(thickness 0.1524)
				)
				(justify left)
			)
		)
		(property "Value" ""
			(at 0 0 90)
			(layer "F.Fab")
			(effects
				(font
					(size 1.27 1.27)
				)
			)
		)
		(duplicate_pad_numbers_are_jumpers no)
		(fp_line
			(start 2.350008 -2.649982)
			(end 2.350008 -2.4892)
			(stroke
				(width 0.1524)
				(type default)
			)
			(layer "F.SilkS")
		)
		(fp_line
			(start -2.350008 -2.649982)
			(end 2.350008 -2.649982)
			(stroke
				(width 0.1524)
				(type default)
			)
			(layer "F.SilkS")
		)
		(fp_line
			(start -2.350008 -2.4384)
			(end -2.350008 -2.649982)
			(stroke
				(width 0.1524)
				(type default)
			)
			(layer "F.SilkS")
		)
		(fp_line
			(start 2.350008 2.4892)
			(end 2.350008 2.649982)
			(stroke
				(width 0.1524)
				(type default)
			)
			(layer "F.SilkS")
		)
		(fp_line
			(start 2.350008 2.649982)
			(end -2.350008 2.649982)
			(stroke
				(width 0.1524)
				(type default)
			)
			(layer "F.SilkS")
		)
		(fp_line
			(start -2.350008 2.649982)
			(end -2.350008 2.413)
			(stroke
				(width 0.1524)
				(type default)
			)
			(layer "F.SilkS")
		)
		(fp_poly
			(pts
				(xy -3.717544 -1.905) (xy -4.758944 -2.3241) (xy -4.758944 -1.524)
			)
			(stroke
				(width 0)
				(type default)
			)
			(fill yes)
			(layer "F.SilkS")
		)
		(fp_line
			(start 2.350008 -2.649982)
			(end 2.350008 2.649982)
			(stroke
				(width 0.1)
				(type default)
			)
			(layer "F.Fab")
		)
		(fp_line
			(start -2.350008 -2.649982)
			(end 2.350008 -2.649982)
			(stroke
				(width 0.1)
				(type default)
			)
			(layer "F.Fab")
		)
		(fp_line
			(start 2.350008 2.649982)
			(end -2.350008 2.649982)
			(stroke
				(width 0.1)
				(type default)
			)
			(layer "F.Fab")
		)
		(fp_line
			(start -2.350008 2.649982)
			(end -2.350008 -2.649982)
			(stroke
				(width 0.1)
				(type default)
			)
			(layer "F.Fab")
		)
		(fp_poly
			(pts
				(xy -3.717544 -1.905) (xy -4.758944 -2.3241) (xy -4.758944 -1.524)
			)
			(stroke
				(width 0)
				(type default)
			)
			(fill yes)
			(layer "F.Fab")
		)
		(pad "1" smd rect
			(at -2.999994 -1.905)
			(size 0.7112 1.1684)
			(layers "F.Cu" "F.Mask" "F.Paste")
			(net "P12V_AUX")
		)
		(pad "2" smd rect
			(at -2.999994 -0.635)
			(size 0.7112 1.1684)
			(layers "F.Cu" "F.Mask" "F.Paste")
			(net "P12V_AUX")
		)
		(pad "3" smd rect
			(at -2.999994 0.635)
			(size 0.7112 1.1684)
			(layers "F.Cu" "F.Mask" "F.Paste")
			(net "P12V_AUX")
		)
		(pad "4" smd rect
			(at -2.999994 1.905)
			(size 0.7112 1.1684)
			(layers "F.Cu" "F.Mask" "F.Paste")
			(net "HS_GATE2_R_4")
		)
		(pad "5" smd circle
			(at 0.925068 0)
			(size 0 0)
			(layers "F.Cu" "F.Mask" "F.Paste")
			(net "P12V_STBY_R2")
		)
		(zone
			(layer "F.Cu")
			(hatch none 0.5)
			(connect_pads
				(clearance 0)
			)
			(min_thickness 0.25)
			(keepout
				(tracks not_allowed)
				(vias allowed)
				(pads allowed)
				(copperpour not_allowed)
				(footprints allowed)
			)
			(placement
				(enabled no)
				(sheetname "")
			)
			(fill
				(thermal_gap 0.5)
				(thermal_bridge_width 0.5)
				(island_removal_mode 0)
			)
			(polygon
				(pts
					(xy 261.176008 -368.482626) (xy 265.494008 -368.482626) (xy 265.976608 -368.482626) (xy 265.976608 -367.580926)
					(xy 260.693408 -367.580926) (xy 260.693408 -368.482626)
				)
			)
		)
	)
	(footprint ""
		(layer "F.Cu")
		(at 104.517698 -380.923546 -90)
		(property "Reference" "R5449"
			(at 0 0 270)
			(layer "F.SilkS")
			(hide yes)
			(effects
				(font
					(size 1.27 1.27)
				)
			)
		)
		(property "Value" ""
			(at 0 0 270)
			(layer "F.Fab")
			(effects
				(font
					(size 1.27 1.27)
				)
			)
		)
		(duplicate_pad_numbers_are_jumpers no)
		(fp_line
			(start 0.7874 0.4064)
			(end -0.7874 0.4064)
			(stroke
				(width 0.1524)
				(type default)
			)
			(layer "F.SilkS")
		)
		(fp_line
			(start -0.7874 -0.4064)
			(end 0.047244 -0.4064)
			(stroke
				(width 0.1524)
				(type default)
			)
			(layer "F.SilkS")
		)
		(fp_line
			(start 0.7874 -0.4064)
			(end 0.7874 0.4064)
			(stroke
				(width 0.1524)
				(type default)
			)
			(layer "F.SilkS")
		)
		(fp_line
			(start -0.67945 0.3048)
			(end -0.67945 -0.305054)
			(stroke
				(width 0.1)
				(type default)
			)
			(layer "F.Fab")
		)
		(fp_line
			(start -0.12065 0.3048)
			(end -0.67945 0.3048)
			(stroke
				(width 0.1)
				(type default)
			)
			(layer "F.Fab")
		)
		(fp_line
			(start 0.120396 0.3048)
			(end 0.120396 0.2794)
			(stroke
				(width 0.1)
				(type default)
			)
			(layer "F.Fab")
		)
		(fp_line
			(start 0.67945 0.3048)
			(end 0.120396 0.3048)
			(stroke
				(width 0.1)
				(type default)
			)
			(layer "F.Fab")
		)
		(fp_line
			(start -0.12065 0.2794)
			(end -0.12065 0.3048)
			(stroke
				(width 0.1)
				(type default)
			)
			(layer "F.Fab")
		)
		(fp_line
			(start 0.120396 0.2794)
			(end -0.12065 0.2794)
			(stroke
				(width 0.1)
				(type default)
			)
			(layer "F.Fab")
		)
		(fp_line
			(start -0.12065 -0.2794)
			(end 0.12065 -0.2794)
			(stroke
				(width 0.1)
				(type default)
			)
			(layer "F.Fab")
		)
		(fp_line
			(start 0.12065 -0.2794)
			(end 0.12065 -0.3048)
			(stroke
				(width 0.1)
				(type default)
			)
			(layer "F.Fab")
		)
		(fp_line
			(start 0.12065 -0.3048)
			(end 0.67945 -0.3048)
			(stroke
				(width 0.1)
				(type default)
			)
			(layer "F.Fab")
		)
		(fp_line
			(start 0.67945 -0.3048)
			(end 0.67945 0.3048)
			(stroke
				(width 0.1)
				(type default)
			)
			(layer "F.Fab")
		)
		(fp_line
			(start -0.67945 -0.305054)
			(end -0.12065 -0.305054)
			(stroke
				(width 0.1)
				(type default)
			)
			(layer "F.Fab")
		)
		(fp_line
			(start -0.12065 -0.305054)
			(end -0.12065 -0.2794)
			(stroke
				(width 0.1)
				(type default)
			)
			(layer "F.Fab")
		)
		(pad "1" smd rect
			(at -0.40005 0 90)
			(size 0.4572 0.508)
			(layers "F.Cu" "F.Mask" "F.Paste")
			(net "USB2_BIC_R_DN")
		)
		(pad "2" smd rect
			(at 0.40005 0 90)
			(size 0.4572 0.508)
			(layers "F.Cu" "F.Mask" "F.Paste")
			(net "USB2_BIC_DN")
		)
	)
	(footprint ""
		(layer "F.Cu")
		(at 344.67038 -280.44902 -90)
		(property "Reference" "PC162"
			(at 0 0 270)
			(layer "F.SilkS")
			(hide yes)
			(effects
				(font
					(size 1.27 1.27)
				)
			)
		)
		(property "Value" ""
			(at 0 0 270)
			(layer "F.Fab")
			(effects
				(font
					(size 1.27 1.27)
				)
			)
		)
		(duplicate_pad_numbers_are_jumpers no)
		(fp_line
			(start -0.7874 0.4064)
			(end -0.7874 -0.4064)
			(stroke
				(width 0.1524)
				(type default)
			)
			(layer "F.SilkS")
		)
		(fp_line
			(start 0.7874 0.4064)
			(end -0.7874 0.4064)
			(stroke
				(width 0.1524)
				(type default)
			)
			(layer "F.SilkS")
		)
		(fp_line
			(start -0.7874 -0.4064)
			(end 0.7874 -0.4064)
			(stroke
				(width 0.1524)
				(type default)
			)
			(layer "F.SilkS")
		)
		(fp_line
			(start 0.7874 -0.4064)
			(end 0.7874 0.4064)
			(stroke
				(width 0.1524)
				(type default)
			)
			(layer "F.SilkS")
		)
		(fp_line
			(start -0.67945 0.3048)
			(end -0.67945 -0.305054)
			(stroke
				(width 0.1)
				(type default)
			)
			(layer "F.Fab")
		)
		(fp_line
			(start -0.12065 0.3048)
			(end -0.67945 0.3048)
			(stroke
				(width 0.1)
				(type default)
			)
			(layer "F.Fab")
		)
		(fp_line
			(start 0.120396 0.3048)
			(end 0.120396 0.2794)
			(stroke
				(width 0.1)
				(type default)
			)
			(layer "F.Fab")
		)
		(fp_line
			(start 0.67945 0.3048)
			(end 0.120396 0.3048)
			(stroke
				(width 0.1)
				(type default)
			)
			(layer "F.Fab")
		)
		(fp_line
			(start -0.12065 0.2794)
			(end -0.12065 0.3048)
			(stroke
				(width 0.1)
				(type default)
			)
			(layer "F.Fab")
		)
		(fp_line
			(start 0.120396 0.2794)
			(end -0.12065 0.2794)
			(stroke
				(width 0.1)
				(type default)
			)
			(layer "F.Fab")
		)
		(fp_line
			(start -0.12065 -0.2794)
			(end 0.12065 -0.2794)
			(stroke
				(width 0.1)
				(type default)
			)
			(layer "F.Fab")
		)
		(fp_line
			(start 0.12065 -0.2794)
			(end 0.12065 -0.3048)
			(stroke
				(width 0.1)
				(type default)
			)
			(layer "F.Fab")
		)
		(fp_line
			(start 0.12065 -0.3048)
			(end 0.67945 -0.3048)
			(stroke
				(width 0.1)
				(type default)
			)
			(layer "F.Fab")
		)
		(fp_line
			(start 0.67945 -0.3048)
			(end 0.67945 0.3048)
			(stroke
				(width 0.1)
				(type default)
			)
			(layer "F.Fab")
		)
		(fp_line
			(start -0.67945 -0.305054)
			(end -0.12065 -0.305054)
			(stroke
				(width 0.1)
				(type default)
			)
			(layer "F.Fab")
		)
		(fp_line
			(start -0.12065 -0.305054)
			(end -0.12065 -0.2794)
			(stroke
				(width 0.1)
				(type default)
			)
			(layer "F.Fab")
		)
		(pad "1" smd circle
			(at -0.40005 0 270)
			(size 0 0)
			(layers "F.Cu" "F.Mask" "F.Paste")
			(net "SW_P0V8_PEX2_PHASE2")
		)
		(pad "2" smd circle
			(at 0.40005 0 270)
			(size 0 0)
			(layers "F.Cu" "F.Mask" "F.Paste")
			(net "SW_P0V8_PEX2_BOOT2_R")
		)
	)
	(footprint ""
		(layer "F.Cu")
		(at 336.80908 -109.432598 -90)
		(property "Reference" "PC807"
			(at 0 0 270)
			(layer "F.SilkS")
			(hide yes)
			(effects
				(font
					(size 1.27 1.27)
				)
			)
		)
		(property "Value" ""
			(at 0 0 270)
			(layer "F.Fab")
			(effects
				(font
					(size 1.27 1.27)
				)
			)
		)
		(duplicate_pad_numbers_are_jumpers no)
		(fp_line
			(start -0.7874 0.4064)
			(end -0.7874 -0.4064)
			(stroke
				(width 0.1524)
				(type default)
			)
			(layer "F.SilkS")
		)
		(fp_line
			(start 0.7874 0.4064)
			(end -0.7874 0.4064)
			(stroke
				(width 0.1524)
				(type default)
			)
			(layer "F.SilkS")
		)
		(fp_line
			(start -0.7874 -0.4064)
			(end 0.7874 -0.4064)
			(stroke
				(width 0.1524)
				(type default)
			)
			(layer "F.SilkS")
		)
		(fp_line
			(start 0.7874 -0.4064)
			(end 0.7874 0.4064)
			(stroke
				(width 0.1524)
				(type default)
			)
			(layer "F.SilkS")
		)
		(fp_line
			(start -0.67945 0.3048)
			(end -0.67945 -0.305054)
			(stroke
				(width 0.1)
				(type default)
			)
			(layer "F.Fab")
		)
		(fp_line
			(start -0.12065 0.3048)
			(end -0.67945 0.3048)
			(stroke
				(width 0.1)
				(type default)
			)
			(layer "F.Fab")
		)
		(fp_line
			(start 0.120396 0.3048)
			(end 0.120396 0.2794)
			(stroke
				(width 0.1)
				(type default)
			)
			(layer "F.Fab")
		)
		(fp_line
			(start 0.67945 0.3048)
			(end 0.120396 0.3048)
			(stroke
				(width 0.1)
				(type default)
			)
			(layer "F.Fab")
		)
		(fp_line
			(start -0.12065 0.2794)
			(end -0.12065 0.3048)
			(stroke
				(width 0.1)
				(type default)
			)
			(layer "F.Fab")
		)
		(fp_line
			(start 0.120396 0.2794)
			(end -0.12065 0.2794)
			(stroke
				(width 0.1)
				(type default)
			)
			(layer "F.Fab")
		)
		(fp_line
			(start -0.12065 -0.2794)
			(end 0.12065 -0.2794)
			(stroke
				(width 0.1)
				(type default)
			)
			(layer "F.Fab")
		)
		(fp_line
			(start 0.12065 -0.2794)
			(end 0.12065 -0.3048)
			(stroke
				(width 0.1)
				(type default)
			)
			(layer "F.Fab")
		)
		(fp_line
			(start 0.12065 -0.3048)
			(end 0.67945 -0.3048)
			(stroke
				(width 0.1)
				(type default)
			)
			(layer "F.Fab")
		)
		(fp_line
			(start 0.67945 -0.3048)
			(end 0.67945 0.3048)
			(stroke
				(width 0.1)
				(type default)
			)
			(layer "F.Fab")
		)
		(fp_line
			(start -0.67945 -0.305054)
			(end -0.12065 -0.305054)
			(stroke
				(width 0.1)
				(type default)
			)
			(layer "F.Fab")
		)
		(fp_line
			(start -0.12065 -0.305054)
			(end -0.12065 -0.2794)
			(stroke
				(width 0.1)
				(type default)
			)
			(layer "F.Fab")
		)
		(pad "1" smd circle
			(at -0.40005 0 270)
			(size 0 0)
			(layers "F.Cu" "F.Mask" "F.Paste")
			(net "P12V_NIC5_R")
		)
		(pad "2" smd circle
			(at 0.40005 0 270)
			(size 0 0)
			(layers "F.Cu" "F.Mask" "F.Paste")
			(net "GND")
		)
	)
)
